# BASEBOARD_FAB2 (Tioga Pass) — schematic netlist excerpt (pin names and nets, part order shuffled) for the footprints in the layout excerpt that follows; sources: Cadence DE-HDL packaged netlist, KiCad conversion of Wiwynn_Tioga_Pass_MB.brd

RF1  RES  1.0K 0.1% CHIP  pkg 0402  page 201 : A = VR_PVCCIN_CPU0_AIREF1 ; B = ISENSE_PVCCIN_CPU0_PH1_IMON
R4D13  RES  27.4 1% CHIP  pkg 0402  page 103 : A = CLK_100M_CPU1_PE_REFCLK_R_DP ; B = CLK_100M_CPU1_PE_REFCLK_DP
C3A2  CAP_A  47UF 4V 20% X5R  pkg 0603V  page 228 : A = PVDDQ_KLM ; B = GND

(kicad_pcb
	(version 20260206)
	(generator "pcbnew")
	(generator_version "10.0")
	(general
		(thickness 1.6)
		(legacy_teardrops no)
	)
	(paper "A4")
	(title_block
		(title "Wiwynn_Tioga_Pass_MB.brd")
		(comment 1 "Tioga Pass / footprints 1293-1295 of 4770")
	)
	(layers
		(0 "F.Cu" signal "TOP")
		(4 "In1.Cu" signal "L2GND")
		(6 "In2.Cu" signal "L3")
		(8 "In3.Cu" signal "L4GND")
		(10 "In4.Cu" signal "L5")
		(12 "In5.Cu" signal "L6GND")
		(14 "In6.Cu" signal "L7VCC")
		(16 "In7.Cu" signal "L8VCC")
		(18 "In8.Cu" signal "L9GND")
		(20 "In9.Cu" signal "L10")
		(22 "In10.Cu" signal "L11GND")
		(24 "In11.Cu" signal "L12")
		(26 "In12.Cu" signal "L13GND")
		(2 "B.Cu" signal "BOTTOM")
		(9 "F.Adhes" user "F.Adhesive")
		(11 "B.Adhes" user "B.Adhesive")
		(13 "F.Paste" user "Package Geometry/Pastemask Top")
		(15 "B.Paste" user "Package Geometry/Pastemask Bottom")
		(5 "F.SilkS" user "Ref Des/Silkscreen Top")
		(7 "B.SilkS" user "Ref Des/Silkscreen Bottom")
		(1 "F.Mask" user "Board Geometry/Soldermask Top")
		(3 "B.Mask" user "Board Geometry/Soldermask Bottom")
		(17 "Dwgs.User" user "User.Drawings")
		(19 "Cmts.User" user "User.Comments")
		(21 "Eco1.User" user "User.Eco1")
		(23 "Eco2.User" user "User.Eco2")
		(25 "Edge.Cuts" user "Board Geometry/Outline")
		(27 "Margin" user)
		(31 "F.CrtYd" user "Package Geometry/Place Bound Top")
		(29 "B.CrtYd" user "Package Geometry/Place Bound Bottom")
		(35 "F.Fab" user "Ref Des/Assembly Top")
		(33 "B.Fab" user "Ref Des/Assembly Bottom")
	)
	(footprint ""
		(layer "F.Cu")
		(at 111.000032 -149.8092 90)
		(property "Reference" "C3A2"
			(at 1.848866 0.752348 90)
			(unlocked yes)
			(layer "F.SilkS")
			(effects
				(font
					(size 1.27 0.9652)
					(thickness 0.1524)
				)
			)
		)
		(property "Value" ""
			(at 0 0 90)
			(layer "F.Fab")
			(effects
				(font
					(size 1.27 1.27)
				)
			)
		)
		(duplicate_pad_numbers_are_jumpers no)
		(fp_rect
			(start -0.500126 1.598422)
			(end 0.500126 -0.201422)
			(stroke
				(width 0)
				(type default)
			)
			(fill no)
			(layer "F.CrtYd")
		)
		(fp_line
			(start 0.500126 -0.201422)
			(end 0.500126 1.598422)
			(stroke
				(width 0.1)
				(type default)
			)
			(layer "F.Fab")
		)
		(fp_line
			(start -0.500126 -0.201422)
			(end 0.500126 -0.201422)
			(stroke
				(width 0.1)
				(type default)
			)
			(layer "F.Fab")
		)
		(fp_line
			(start 0.500126 1.598422)
			(end -0.500126 1.598422)
			(stroke
				(width 0.1)
				(type default)
			)
			(layer "F.Fab")
		)
		(fp_line
			(start -0.500126 1.598422)
			(end -0.500126 -0.201422)
			(stroke
				(width 0.1)
				(type default)
			)
			(layer "F.Fab")
		)
		(pad "1" smd rect
			(at 0 0)
			(size 0.889 0.9906)
			(layers "F.Cu" "F.Mask" "F.Paste")
			(net "PVDDQ_KLM")
		)
		(pad "2" smd rect
			(at 0 1.397)
			(size 0.889 0.9906)
			(layers "F.Cu" "F.Mask" "F.Paste")
			(net "GND")
		)
		(zone
			(layer "F.Cu")
			(hatch none 0.5)
			(connect_pads
				(clearance 0)
			)
			(min_thickness 0.25)
			(keepout
				(tracks allowed)
				(vias not_allowed)
				(pads allowed)
				(copperpour not_allowed)
				(footprints allowed)
			)
			(placement
				(enabled no)
				(sheetname "")
			)
			(fill
				(thermal_gap 0.5)
				(thermal_bridge_width 0.5)
				(island_removal_mode 0)
			)
			(polygon
				(pts
					(xy 111.952532 -149.3139) (xy 111.952532 -150.3045) (xy 111.444532 -150.3045) (xy 111.444532 -149.3139)
				)
			)
		)
		(zone
			(layer "F.Cu")
			(hatch none 0.5)
			(connect_pads
				(clearance 0)
			)
			(min_thickness 0.25)
			(keepout
				(tracks not_allowed)
				(vias allowed)
				(pads allowed)
				(copperpour not_allowed)
				(footprints allowed)
			)
			(placement
				(enabled no)
				(sheetname "")
			)
			(fill
				(thermal_gap 0.5)
				(thermal_bridge_width 0.5)
				(island_removal_mode 0)
			)
			(polygon
				(pts
					(xy 111.952532 -149.3139) (xy 111.952532 -150.3045) (xy 111.444532 -150.3045) (xy 111.444532 -149.3139)
				)
			)
		)
	)
	(footprint ""
		(layer "F.Cu")
		(at 163.576 -83.058 -90)
		(property "Reference" "R4D13"
			(at 0 0 270)
			(layer "F.SilkS")
			(hide yes)
			(effects
				(font
					(size 1.27 1.27)
				)
			)
		)
		(property "Value" ""
			(at 0 0 270)
			(layer "F.Fab")
			(effects
				(font
					(size 1.27 1.27)
				)
			)
		)
		(duplicate_pad_numbers_are_jumpers no)
		(fp_poly
			(pts
				(xy -0.2794 -0.1016) (xy 0.2794 -0.1016) (xy 0.2794 0.9906) (xy -0.2794 0.9906)
			)
			(stroke
				(width 0)
				(type default)
			)
			(fill no)
			(layer "F.CrtYd")
		)
		(fp_line
			(start -0.2794 0.9906)
			(end 0.2794 0.9906)
			(stroke
				(width 0.1)
				(type default)
			)
			(layer "F.Fab")
		)
		(fp_line
			(start 0.2794 0.9906)
			(end 0.2794 -0.1016)
			(stroke
				(width 0.1)
				(type default)
			)
			(layer "F.Fab")
		)
		(fp_line
			(start -0.2794 -0.1016)
			(end -0.2794 0.9906)
			(stroke
				(width 0.1)
				(type default)
			)
			(layer "F.Fab")
		)
		(fp_line
			(start 0.2794 -0.1016)
			(end -0.2794 -0.1016)
			(stroke
				(width 0.1)
				(type default)
			)
			(layer "F.Fab")
		)
		(pad "1" smd rect
			(at 0 0 270)
			(size 0.508 0.508)
			(layers "F.Cu" "F.Mask" "F.Paste")
			(net "CLK_100M_CPU1_PE_REFCLK_R_DP")
		)
		(pad "2" smd rect
			(at 0 0.889 270)
			(size 0.508 0.508)
			(layers "F.Cu" "F.Mask" "F.Paste")
			(net "CLK_100M_CPU1_PE_REFCLK_DP")
		)
		(zone
			(layer "F.Cu")
			(hatch none 0.5)
			(connect_pads
				(clearance 0)
			)
			(min_thickness 0.25)
			(keepout
				(tracks not_allowed)
				(vias allowed)
				(pads allowed)
				(copperpour not_allowed)
				(footprints allowed)
			)
			(placement
				(enabled no)
				(sheetname "")
			)
			(fill
				(thermal_gap 0.5)
				(thermal_bridge_width 0.5)
				(island_removal_mode 0)
			)
			(polygon
				(pts
					(xy 162.941 -83.312) (xy 162.941 -82.804) (xy 163.322 -82.804) (xy 163.322 -83.312)
				)
			)
		)
		(zone
			(layer "F.Cu")
			(hatch none 0.5)
			(connect_pads
				(clearance 0)
			)
			(min_thickness 0.25)
			(keepout
				(tracks allowed)
				(vias not_allowed)
				(pads allowed)
				(copperpour not_allowed)
				(footprints allowed)
			)
			(placement
				(enabled no)
				(sheetname "")
			)
			(fill
				(thermal_gap 0.5)
				(thermal_bridge_width 0.5)
				(island_removal_mode 0)
			)
			(polygon
				(pts
					(xy 163.322 -83.312) (xy 163.322 -82.804) (xy 162.941 -82.804) (xy 162.941 -83.312)
				)
			)
		)
	)
	(footprint ""
		(layer "F.Cu")
		(at 188.137038 -65.27546 180)
		(property "Reference" "RF1"
			(at -0.8382 -0.67818 180)
			(unlocked yes)
			(layer "F.SilkS")
			(effects
				(font
					(size 0.4064 0.254)
					(thickness 0.1524)
				)
				(justify left)
			)
		)
		(property "Value" ""
			(at 0 0 180)
			(layer "F.Fab")
			(effects
				(font
					(size 1.27 1.27)
				)
			)
		)
		(duplicate_pad_numbers_are_jumpers no)
		(fp_poly
			(pts
				(xy -0.2794 -0.1016) (xy 0.2794 -0.1016) (xy 0.2794 0.9906) (xy -0.2794 0.9906)
			)
			(stroke
				(width 0)
				(type default)
			)
			(fill no)
			(layer "F.CrtYd")
		)
		(fp_line
			(start 0.2794 0.9906)
			(end 0.2794 -0.1016)
			(stroke
				(width 0.1)
				(type default)
			)
			(layer "F.Fab")
		)
		(fp_line
			(start 0.2794 -0.1016)
			(end -0.2794 -0.1016)
			(stroke
				(width 0.1)
				(type default)
			)
			(layer "F.Fab")
		)
		(fp_line
			(start -0.2794 0.9906)
			(end 0.2794 0.9906)
			(stroke
				(width 0.1)
				(type default)
			)
			(layer "F.Fab")
		)
		(fp_line
			(start -0.2794 -0.1016)
			(end -0.2794 0.9906)
			(stroke
				(width 0.1)
				(type default)
			)
			(layer "F.Fab")
		)
		(pad "1" smd rect
			(at 0 0 180)
			(size 0.508 0.508)
			(layers "F.Cu" "F.Mask" "F.Paste")
			(net "VR_PVCCIN_CPU0_AIREF1")
		)
		(pad "2" smd rect
			(at 0 0.889 180)
			(size 0.508 0.508)
			(layers "F.Cu" "F.Mask" "F.Paste")
			(net "ISENSE_PVCCIN_CPU0_PH1_IMON")
		)
		(zone
			(layer "F.Cu")
			(hatch none 0.5)
			(connect_pads
				(clearance 0)
			)
			(min_thickness 0.25)
			(keepout
				(tracks not_allowed)
				(vias allowed)
				(pads allowed)
				(copperpour not_allowed)
				(footprints allowed)
			)
			(placement
				(enabled no)
				(sheetname "")
			)
			(fill
				(thermal_gap 0.5)
				(thermal_bridge_width 0.5)
				(island_removal_mode 0)
			)
			(polygon
				(pts
					(xy 188.391038 -65.91046) (xy 187.883038 -65.91046) (xy 187.883038 -65.52946) (xy 188.391038 -65.52946)
				)
			)
		)
		(zone
			(layer "F.Cu")
			(hatch none 0.5)
			(connect_pads
				(clearance 0)
			)
			(min_thickness 0.25)
			(keepout
				(tracks allowed)
				(vias not_allowed)
				(pads allowed)
				(copperpour not_allowed)
				(footprints allowed)
			)
			(placement
				(enabled no)
				(sheetname "")
			)
			(fill
				(thermal_gap 0.5)
				(thermal_bridge_width 0.5)
				(island_removal_mode 0)
			)
			(polygon
				(pts
					(xy 188.391038 -65.52946) (xy 187.883038 -65.52946) (xy 187.883038 -65.91046) (xy 188.391038 -65.91046)
				)
			)
		)
	)
)
